FILE_TYPE = MULTI_PHYS_TABLE;
PART 'ADC128D818'
{==============================================================================================================================================================}
:PACK_TYPE |MATERIAL  |PART_NUMBER      = EnvComp |PART_NUMBER   |JEDEC_TYPE          |CLASS  |DESCRIPTION                   |HEIGHT      |COMPONENT_TYPE| LPID   | SPEED_URL | Status |RPL| AML | Bus_Unit | Days;
{==============================================================================================================================================================}
'SM'       | 'IC'     | 'H63642-001'(!) = ''      | 'H63642-001' |  'TSSOP16_18_65MA' | 'IC'  | 'IC, LIN,TSSOP,ADC128D8,ADC' | '0.047 IN' | 'SUB50'      | '1095' | 'http://speed.intel.com:8081/speed/module/pdm/item/pdm_item_detail_direct.asp?item_cde=H63642-001&item_rev=01&url_param=unused' | '' | '' | '' | '' | '' 
'SM'       | 'EMPTY'  | 'H63642-001'(!) = ''      | 'H63642-001' |  'TSSOP16_18_65MA' | 'IO'  | 'IC, LIN,TSSOP,ADC128D8,ADC' | '0.047 IN' | 'SUB50'      | '1095' | 'http://speed.intel.com:8081/speed/module/pdm/item/pdm_item_detail_direct.asp?item_cde=H63642-001&item_rev=01&url_param=unused' | '' | '' | '' | '' | '' 
END_PART
END.
